# T6G (Grand Teton) — schematic netlist excerpt (pin names and nets, part order shuffled) for the footprints in the layout excerpt that follows; sources: Cadence DE-HDL packaged netlist, KiCad conversion of 04192023_DAF0TMB3IC0_F0TG_MB_C_brd_V02_OCP.brd

R2906  Q_RES  0 5% CHIP  pkg 0402LF  page 240 : A = FM_GPU_HSC_EN_BUF_R1 ; B = FM_GPU_HSC_EN_BUF
R8220  Q_RES  1K 1% EMPTY  pkg 0402LF  page 217 : A = PVDD18_S5_P1 ; B = SVID_PVDDCR_CPU1_P1_SVTO

(kicad_pcb
	(version 20260206)
	(generator "pcbnew")
	(generator_version "10.0")
	(general
		(thickness 1.6)
		(legacy_teardrops no)
	)
	(paper "A4")
	(title_block
		(title "04192023_DAF0TMB3IC0_F0TG_MB_C_brd_V02_OCP.brd")
		(comment 1 "Grand Teton / footprints 8046-8047 of 8354")
	)
	(layers
		(0 "F.Cu" signal "TOP")
		(4 "In1.Cu" signal "GND")
		(6 "In2.Cu" signal "IN1")
		(8 "In3.Cu" signal "GND1")
		(10 "In4.Cu" signal "IN2")
		(12 "In5.Cu" signal "GND2")
		(14 "In6.Cu" signal "IN3")
		(16 "In7.Cu" signal "GND3")
		(18 "In8.Cu" signal "VCC")
		(20 "In9.Cu" signal "VCC1")
		(22 "In10.Cu" signal "GND4")
		(24 "In11.Cu" signal "IN4")
		(26 "In12.Cu" signal "GND5")
		(28 "In13.Cu" signal "IN5")
		(30 "In14.Cu" signal "GND6")
		(32 "In15.Cu" signal "IN6")
		(34 "In16.Cu" signal "GND7")
		(2 "B.Cu" signal "BOTTOM")
		(9 "F.Adhes" user "F.Adhesive")
		(11 "B.Adhes" user "B.Adhesive")
		(13 "F.Paste" user "Package Geometry/Pastemask Top")
		(15 "B.Paste" user "Package Geometry/Pastemask Bottom")
		(5 "F.SilkS" user "Ref Des/Silkscreen Top")
		(7 "B.SilkS" user "Ref Des/Silkscreen Bottom")
		(1 "F.Mask" user "Board Geometry/Soldermask Top")
		(3 "B.Mask" user "Board Geometry/Soldermask Bottom")
		(17 "Dwgs.User" user "User.Drawings")
		(19 "Cmts.User" user "User.Comments")
		(21 "Eco1.User" user "User.Eco1")
		(23 "Eco2.User" user "User.Eco2")
		(25 "Edge.Cuts" user "Board Geometry/Outline")
		(27 "Margin" user)
		(31 "F.CrtYd" user "Package Geometry/Place Bound Top")
		(29 "B.CrtYd" user "Package Geometry/Place Bound Bottom")
		(35 "F.Fab" user "Ref Des/Assembly Top")
		(33 "B.Fab" user "Ref Des/Assembly Bottom")
	)
	(footprint ""
		(layer "B.Cu")
		(at 237.692692 -422.849548 90)
		(property "Reference" "R2906"
			(at 0 0 90)
			(layer "B.SilkS")
			(hide yes)
			(effects
				(font
					(size 1.27 1.27)
				)
				(justify mirror)
			)
		)
		(property "Value" ""
			(at 0 0 90)
			(layer "B.Fab")
			(effects
				(font
					(size 1.27 1.27)
				)
				(justify mirror)
			)
		)
		(duplicate_pad_numbers_are_jumpers no)
		(fp_line
			(start 0.7874 -0.4064)
			(end -0.7874 -0.4064)
			(stroke
				(width 0.1524)
				(type default)
			)
			(layer "B.SilkS")
		)
		(fp_line
			(start -0.7874 -0.4064)
			(end -0.7874 0.4064)
			(stroke
				(width 0.1524)
				(type default)
			)
			(layer "B.SilkS")
		)
		(fp_line
			(start 0.7874 0.4064)
			(end 0.7874 -0.4064)
			(stroke
				(width 0.1524)
				(type default)
			)
			(layer "B.SilkS")
		)
		(fp_line
			(start -0.7874 0.4064)
			(end 0.7874 0.4064)
			(stroke
				(width 0.1524)
				(type default)
			)
			(layer "B.SilkS")
		)
		(fp_line
			(start 0.67945 -0.305054)
			(end 0.12065 -0.305054)
			(stroke
				(width 0.1)
				(type default)
			)
			(layer "B.Fab")
		)
		(fp_line
			(start 0.12065 -0.305054)
			(end 0.12065 -0.2794)
			(stroke
				(width 0.1)
				(type default)
			)
			(layer "B.Fab")
		)
		(fp_line
			(start -0.12065 -0.3048)
			(end -0.67945 -0.3048)
			(stroke
				(width 0.1)
				(type default)
			)
			(layer "B.Fab")
		)
		(fp_line
			(start -0.67945 -0.3048)
			(end -0.67945 0.3048)
			(stroke
				(width 0.1)
				(type default)
			)
			(layer "B.Fab")
		)
		(fp_line
			(start 0.12065 -0.2794)
			(end -0.12065 -0.2794)
			(stroke
				(width 0.1)
				(type default)
			)
			(layer "B.Fab")
		)
		(fp_line
			(start -0.12065 -0.2794)
			(end -0.12065 -0.3048)
			(stroke
				(width 0.1)
				(type default)
			)
			(layer "B.Fab")
		)
		(fp_line
			(start 0.12065 0.2794)
			(end 0.12065 0.3048)
			(stroke
				(width 0.1)
				(type default)
			)
			(layer "B.Fab")
		)
		(fp_line
			(start -0.120396 0.2794)
			(end 0.12065 0.2794)
			(stroke
				(width 0.1)
				(type default)
			)
			(layer "B.Fab")
		)
		(fp_line
			(start 0.67945 0.3048)
			(end 0.67945 -0.305054)
			(stroke
				(width 0.1)
				(type default)
			)
			(layer "B.Fab")
		)
		(fp_line
			(start 0.12065 0.3048)
			(end 0.67945 0.3048)
			(stroke
				(width 0.1)
				(type default)
			)
			(layer "B.Fab")
		)
		(fp_line
			(start -0.120396 0.3048)
			(end -0.120396 0.2794)
			(stroke
				(width 0.1)
				(type default)
			)
			(layer "B.Fab")
		)
		(fp_line
			(start -0.67945 0.3048)
			(end -0.120396 0.3048)
			(stroke
				(width 0.1)
				(type default)
			)
			(layer "B.Fab")
		)
		(pad "1" smd circle
			(at 0.40005 0 270)
			(size 0 0)
			(layers "B.Cu" "B.Mask" "B.Paste")
			(net "FM_GPU_HSC_EN_BUF_R1")
		)
		(pad "2" smd circle
			(at -0.40005 0 270)
			(size 0 0)
			(layers "B.Cu" "B.Mask" "B.Paste")
			(net "FM_GPU_HSC_EN_BUF")
		)
	)
	(footprint ""
		(layer "B.Cu")
		(at 22.479 -358.775 180)
		(property "Reference" "R8220"
			(at 0 0 0)
			(layer "B.SilkS")
			(hide yes)
			(effects
				(font
					(size 1.27 1.27)
				)
				(justify mirror)
			)
		)
		(property "Value" ""
			(at 0 0 0)
			(layer "B.Fab")
			(effects
				(font
					(size 1.27 1.27)
				)
				(justify mirror)
			)
		)
		(duplicate_pad_numbers_are_jumpers no)
		(fp_line
			(start 0.7874 0.4064)
			(end 0.7874 -0.4064)
			(stroke
				(width 0.1524)
				(type default)
			)
			(layer "B.SilkS")
		)
		(fp_line
			(start 0.7874 -0.4064)
			(end -0.7874 -0.4064)
			(stroke
				(width 0.1524)
				(type default)
			)
			(layer "B.SilkS")
		)
		(fp_line
			(start -0.7874 0.4064)
			(end 0.7874 0.4064)
			(stroke
				(width 0.1524)
				(type default)
			)
			(layer "B.SilkS")
		)
		(fp_line
			(start -0.7874 -0.4064)
			(end -0.7874 0.4064)
			(stroke
				(width 0.1524)
				(type default)
			)
			(layer "B.SilkS")
		)
		(fp_line
			(start 0.67945 0.3048)
			(end 0.67945 -0.305054)
			(stroke
				(width 0.1)
				(type default)
			)
			(layer "B.Fab")
		)
		(fp_line
			(start 0.67945 -0.305054)
			(end 0.12065 -0.305054)
			(stroke
				(width 0.1)
				(type default)
			)
			(layer "B.Fab")
		)
		(fp_line
			(start 0.12065 0.3048)
			(end 0.67945 0.3048)
			(stroke
				(width 0.1)
				(type default)
			)
			(layer "B.Fab")
		)
		(fp_line
			(start 0.12065 0.2794)
			(end 0.12065 0.3048)
			(stroke
				(width 0.1)
				(type default)
			)
			(layer "B.Fab")
		)
		(fp_line
			(start 0.12065 -0.2794)
			(end -0.12065 -0.2794)
			(stroke
				(width 0.1)
				(type default)
			)
			(layer "B.Fab")
		)
		(fp_line
			(start 0.12065 -0.305054)
			(end 0.12065 -0.2794)
			(stroke
				(width 0.1)
				(type default)
			)
			(layer "B.Fab")
		)
		(fp_line
			(start -0.120396 0.3048)
			(end -0.120396 0.2794)
			(stroke
				(width 0.1)
				(type default)
			)
			(layer "B.Fab")
		)
		(fp_line
			(start -0.120396 0.2794)
			(end 0.12065 0.2794)
			(stroke
				(width 0.1)
				(type default)
			)
			(layer "B.Fab")
		)
		(fp_line
			(start -0.12065 -0.2794)
			(end -0.12065 -0.3048)
			(stroke
				(width 0.1)
				(type default)
			)
			(layer "B.Fab")
		)
		(fp_line
			(start -0.12065 -0.3048)
			(end -0.67945 -0.3048)
			(stroke
				(width 0.1)
				(type default)
			)
			(layer "B.Fab")
		)
		(fp_line
			(start -0.67945 0.3048)
			(end -0.120396 0.3048)
			(stroke
				(width 0.1)
				(type default)
			)
			(layer "B.Fab")
		)
		(fp_line
			(start -0.67945 -0.3048)
			(end -0.67945 0.3048)
			(stroke
				(width 0.1)
				(type default)
			)
			(layer "B.Fab")
		)
		(pad "1" smd circle
			(at 0.40005 0)
			(size 0 0)
			(layers "B.Cu" "B.Mask" "B.Paste")
			(net "PVDD18_S5_P1")
		)
		(pad "2" smd circle
			(at -0.40005 0)
			(size 0 0)
			(layers "B.Cu" "B.Mask" "B.Paste")
			(net "SVID_PVDDCR_CPU1_P1_SVTO")
		)
	)
)
